# BASEBOARD_FAB2 (Tioga Pass) — schematic netlist excerpt (pin names and nets, part order shuffled) for the footprints in the layout excerpt that follows; sources: Cadence DE-HDL packaged netlist, KiCad conversion of Wiwynn_Tioga_Pass_MB.brd

C1W19  CAP_A  0.1UF 16V 10% X7R  pkg 0402V  page 176 : A = P3V3_STBY ; B = GND
C2N15  CAP_A  1.0UF 6.3V 10% X6S  pkg 0402V  page 130 : A = P1V8_PCH_STBY ; B = GND
R6P45  RES  33.2 1% CHIP  pkg 0402  page 201 : A = IRQ_PVCCIN_CPU0_VRHOT_LVC3_R_N ; B = IRQ_PVCCIN_CPU0_VRHOT_LVC3_N

(kicad_pcb
	(version 20260206)
	(generator "pcbnew")
	(generator_version "10.0")
	(general
		(thickness 1.6)
		(legacy_teardrops no)
	)
	(paper "A4")
	(title_block
		(title "Wiwynn_Tioga_Pass_MB.brd")
		(comment 1 "Tioga Pass / footprints 4668-4670 of 4770")
	)
	(layers
		(0 "F.Cu" signal "TOP")
		(4 "In1.Cu" signal "L2GND")
		(6 "In2.Cu" signal "L3")
		(8 "In3.Cu" signal "L4GND")
		(10 "In4.Cu" signal "L5")
		(12 "In5.Cu" signal "L6GND")
		(14 "In6.Cu" signal "L7VCC")
		(16 "In7.Cu" signal "L8VCC")
		(18 "In8.Cu" signal "L9GND")
		(20 "In9.Cu" signal "L10")
		(22 "In10.Cu" signal "L11GND")
		(24 "In11.Cu" signal "L12")
		(26 "In12.Cu" signal "L13GND")
		(2 "B.Cu" signal "BOTTOM")
		(9 "F.Adhes" user "F.Adhesive")
		(11 "B.Adhes" user "B.Adhesive")
		(13 "F.Paste" user "Package Geometry/Pastemask Top")
		(15 "B.Paste" user "Package Geometry/Pastemask Bottom")
		(5 "F.SilkS" user "Ref Des/Silkscreen Top")
		(7 "B.SilkS" user "Ref Des/Silkscreen Bottom")
		(1 "F.Mask" user "Board Geometry/Soldermask Top")
		(3 "B.Mask" user "Board Geometry/Soldermask Bottom")
		(17 "Dwgs.User" user "User.Drawings")
		(19 "Cmts.User" user "User.Comments")
		(21 "Eco1.User" user "User.Eco1")
		(23 "Eco2.User" user "User.Eco2")
		(25 "Edge.Cuts" user "Board Geometry/Outline")
		(27 "Margin" user)
		(31 "F.CrtYd" user "Package Geometry/Place Bound Top")
		(29 "B.CrtYd" user "Package Geometry/Place Bound Bottom")
		(35 "F.Fab" user "Ref Des/Assembly Top")
		(33 "B.Fab" user "Ref Des/Assembly Bottom")
	)
	(footprint ""
		(layer "B.Cu")
		(at 473.130118 -134.958074 -90)
		(property "Reference" "C1W19"
			(at 0.8382 -0.67818 270)
			(unlocked yes)
			(layer "B.SilkS")
			(effects
				(font
					(size 0.4064 0.254)
					(thickness 0.1524)
				)
				(justify left mirror)
			)
		)
		(property "Value" ""
			(at 0 0 90)
			(layer "B.Fab")
			(effects
				(font
					(size 1.27 1.27)
				)
				(justify mirror)
			)
		)
		(duplicate_pad_numbers_are_jumpers no)
		(fp_poly
			(pts
				(xy -0.3048 -0.1016) (xy -0.3048 0.9906) (xy 0.3048 0.9906) (xy 0.3048 -0.1016)
			)
			(stroke
				(width 0)
				(type default)
			)
			(fill no)
			(layer "B.CrtYd")
		)
		(fp_line
			(start -0.3048 0.9906)
			(end -0.3048 -0.1016)
			(stroke
				(width 0.1)
				(type default)
			)
			(layer "B.Fab")
		)
		(fp_line
			(start 0.3048 0.9906)
			(end -0.3048 0.9906)
			(stroke
				(width 0.1)
				(type default)
			)
			(layer "B.Fab")
		)
		(fp_line
			(start -0.3048 -0.1016)
			(end 0.3048 -0.1016)
			(stroke
				(width 0.1)
				(type default)
			)
			(layer "B.Fab")
		)
		(fp_line
			(start 0.3048 -0.1016)
			(end 0.3048 0.9906)
			(stroke
				(width 0.1)
				(type default)
			)
			(layer "B.Fab")
		)
		(pad "1" smd rect
			(at 0 0 90)
			(size 0.508 0.508)
			(layers "B.Cu" "B.Mask" "B.Paste")
			(net "P3V3_STBY")
		)
		(pad "2" smd rect
			(at 0 0.889 90)
			(size 0.508 0.508)
			(layers "B.Cu" "B.Mask" "B.Paste")
			(net "GND")
		)
		(zone
			(layer "B.Cu")
			(hatch none 0.5)
			(connect_pads
				(clearance 0)
			)
			(min_thickness 0.25)
			(keepout
				(tracks not_allowed)
				(vias allowed)
				(pads allowed)
				(copperpour not_allowed)
				(footprints allowed)
			)
			(placement
				(enabled no)
				(sheetname "")
			)
			(fill
				(thermal_gap 0.5)
				(thermal_bridge_width 0.5)
				(island_removal_mode 0)
			)
			(polygon
				(pts
					(xy 472.495118 -134.704074) (xy 472.495118 -135.212074) (xy 472.876118 -135.212074) (xy 472.876118 -134.704074)
				)
			)
		)
		(zone
			(layer "B.Cu")
			(hatch none 0.5)
			(connect_pads
				(clearance 0)
			)
			(min_thickness 0.25)
			(keepout
				(tracks allowed)
				(vias not_allowed)
				(pads allowed)
				(copperpour not_allowed)
				(footprints allowed)
			)
			(placement
				(enabled no)
				(sheetname "")
			)
			(fill
				(thermal_gap 0.5)
				(thermal_bridge_width 0.5)
				(island_removal_mode 0)
			)
			(polygon
				(pts
					(xy 472.876118 -134.704074) (xy 472.876118 -135.212074) (xy 472.495118 -135.212074) (xy 472.495118 -134.704074)
				)
			)
		)
	)
	(footprint ""
		(layer "B.Cu")
		(at 180.467 -65.024)
		(property "Reference" "R6P45"
			(at 0 0 0)
			(layer "B.SilkS")
			(hide yes)
			(effects
				(font
					(size 1.27 1.27)
				)
				(justify mirror)
			)
		)
		(property "Value" ""
			(at 0 0 0)
			(layer "B.Fab")
			(effects
				(font
					(size 1.27 1.27)
				)
				(justify mirror)
			)
		)
		(duplicate_pad_numbers_are_jumpers no)
		(fp_poly
			(pts
				(xy 0.2794 -0.1016) (xy -0.2794 -0.1016) (xy -0.2794 0.9906) (xy 0.2794 0.9906)
			)
			(stroke
				(width 0)
				(type default)
			)
			(fill no)
			(layer "B.CrtYd")
		)
		(fp_line
			(start -0.2794 -0.1016)
			(end 0.2794 -0.1016)
			(stroke
				(width 0.1)
				(type default)
			)
			(layer "B.Fab")
		)
		(fp_line
			(start -0.2794 0.9906)
			(end -0.2794 -0.1016)
			(stroke
				(width 0.1)
				(type default)
			)
			(layer "B.Fab")
		)
		(fp_line
			(start 0.2794 -0.1016)
			(end 0.2794 0.9906)
			(stroke
				(width 0.1)
				(type default)
			)
			(layer "B.Fab")
		)
		(fp_line
			(start 0.2794 0.9906)
			(end -0.2794 0.9906)
			(stroke
				(width 0.1)
				(type default)
			)
			(layer "B.Fab")
		)
		(pad "1" smd rect
			(at 0 0 180)
			(size 0.508 0.508)
			(layers "B.Cu" "B.Mask" "B.Paste")
			(net "IRQ_PVCCIN_CPU0_VRHOT_LVC3_R_N")
		)
		(pad "2" smd rect
			(at 0 0.889 180)
			(size 0.508 0.508)
			(layers "B.Cu" "B.Mask" "B.Paste")
			(net "IRQ_PVCCIN_CPU0_VRHOT_LVC3_N")
		)
		(zone
			(layer "B.Cu")
			(hatch none 0.5)
			(connect_pads
				(clearance 0)
			)
			(min_thickness 0.25)
			(keepout
				(tracks allowed)
				(vias not_allowed)
				(pads allowed)
				(copperpour not_allowed)
				(footprints allowed)
			)
			(placement
				(enabled no)
				(sheetname "")
			)
			(fill
				(thermal_gap 0.5)
				(thermal_bridge_width 0.5)
				(island_removal_mode 0)
			)
			(polygon
				(pts
					(xy 180.721 -64.77) (xy 180.213 -64.77) (xy 180.213 -64.389) (xy 180.721 -64.389)
				)
			)
		)
		(zone
			(layer "B.Cu")
			(hatch none 0.5)
			(connect_pads
				(clearance 0)
			)
			(min_thickness 0.25)
			(keepout
				(tracks not_allowed)
				(vias allowed)
				(pads allowed)
				(copperpour not_allowed)
				(footprints allowed)
			)
			(placement
				(enabled no)
				(sheetname "")
			)
			(fill
				(thermal_gap 0.5)
				(thermal_bridge_width 0.5)
				(island_removal_mode 0)
			)
			(polygon
				(pts
					(xy 180.721 -64.389) (xy 180.213 -64.389) (xy 180.213 -64.77) (xy 180.721 -64.77)
				)
			)
		)
	)
	(footprint ""
		(layer "B.Cu")
		(at 390.93775 -106.25455 180)
		(property "Reference" "C2N15"
			(at 0 0 0)
			(layer "B.SilkS")
			(hide yes)
			(effects
				(font
					(size 1.27 1.27)
				)
				(justify mirror)
			)
		)
		(property "Value" ""
			(at 0 0 0)
			(layer "B.Fab")
			(effects
				(font
					(size 1.27 1.27)
				)
				(justify mirror)
			)
		)
		(duplicate_pad_numbers_are_jumpers no)
		(fp_rect
			(start 0.2794 0.9144)
			(end -0.2794 -0.1143)
			(stroke
				(width 0)
				(type default)
			)
			(fill no)
			(layer "B.CrtYd")
		)
		(fp_line
			(start 0.2794 0.9144)
			(end 0.2794 -0.1143)
			(stroke
				(width 0.1)
				(type default)
			)
			(layer "B.Fab")
		)
		(fp_line
			(start 0.2794 -0.1143)
			(end -0.2794 -0.1143)
			(stroke
				(width 0.1)
				(type default)
			)
			(layer "B.Fab")
		)
		(fp_line
			(start -0.2794 0.9144)
			(end 0.2794 0.9144)
			(stroke
				(width 0.1)
				(type default)
			)
			(layer "B.Fab")
		)
		(fp_line
			(start -0.2794 -0.1143)
			(end -0.2794 0.9144)
			(stroke
				(width 0.1)
				(type default)
			)
			(layer "B.Fab")
		)
		(pad "1" smd custom
			(at 0 0 90)
			(size 0.10414 0.10414)
			(layers "B.Cu" "B.Mask" "B.Paste")
			(net "P1V8_PCH_STBY")
			(options
				(clearance outline)
				(anchor circle)
			)
			(primitives
				(gr_poly
					(pts
						(xy -0.20828 -0.08636) (xy -0.20828 0.08636) (xy -0.08636 0.20828) (xy 0.086614 0.20828) (xy 0.20828 0.086614)
						(xy 0.20828 -0.08636) (xy 0.08636 -0.20828) (xy -0.08636 -0.20828)
					)
					(width 0)
					(fill yes)
				)
			)
		)
		(pad "2" smd custom
			(at 0 0.8001 90)
			(size 0.10414 0.10414)
			(layers "B.Cu" "B.Mask" "B.Paste")
			(net "GND")
			(options
				(clearance outline)
				(anchor circle)
			)
			(primitives
				(gr_poly
					(pts
						(xy -0.20828 -0.08636) (xy -0.20828 0.08636) (xy -0.08636 0.20828) (xy 0.086614 0.20828) (xy 0.20828 0.086614)
						(xy 0.20828 -0.08636) (xy 0.08636 -0.20828) (xy -0.08636 -0.20828)
					)
					(width 0)
					(fill yes)
				)
			)
		)
		(zone
			(layer "B.Cu")
			(hatch none 0.5)
			(connect_pads
				(clearance 0)
			)
			(min_thickness 0.25)
			(keepout
				(tracks not_allowed)
				(vias allowed)
				(pads allowed)
				(copperpour not_allowed)
				(footprints allowed)
			)
			(placement
				(enabled no)
				(sheetname "")
			)
			(fill
				(thermal_gap 0.5)
				(thermal_bridge_width 0.5)
				(island_removal_mode 0)
			)
			(polygon
				(pts
					(xy 390.85012 -106.4641) (xy 390.85012 -106.8451) (xy 391.02538 -106.8451) (xy 391.025634 -106.4641)
				)
			)
		)
		(zone
			(layer "B.Cu")
			(hatch none 0.5)
			(connect_pads
				(clearance 0)
			)
			(min_thickness 0.25)
			(keepout
				(tracks allowed)
				(vias not_allowed)
				(pads allowed)
				(copperpour not_allowed)
				(footprints allowed)
			)
			(placement
				(enabled no)
				(sheetname "")
			)
			(fill
				(thermal_gap 0.5)
				(thermal_bridge_width 0.5)
				(island_removal_mode 0)
			)
			(polygon
				(pts
					(xy 390.85012 -106.4641) (xy 390.85012 -106.8451) (xy 391.02538 -106.8451) (xy 391.025634 -106.4641)
				)
			)
		)
	)
)
